(kicad_pcb
	(version 20260206)
	(generator "pcbnew")
	(generator_version "10.0")
	(general
		(thickness 1.6)
		(legacy_teardrops no)
	)
	(paper "A4")
	(title_block
		(title "03242023_DA0F0TMBIJ0_F0T_Motherboard_J_brd_V01_OCP.brd")
		(comment 1 "Grand Teton / footprints 3047-3053 of 6105")
	)
	(layers
		(0 "F.Cu" signal "TOP")
		(4 "In1.Cu" signal "GND")
		(6 "In2.Cu" signal "IN1")
		(8 "In3.Cu" signal "GND1")
		(10 "In4.Cu" signal "IN2")
		(12 "In5.Cu" signal "GND2")
		(14 "In6.Cu" signal "IN3")
		(16 "In7.Cu" signal "GND3")
		(18 "In8.Cu" signal "VCC")
		(20 "In9.Cu" signal "VCC1")
		(22 "In10.Cu" signal "GND4")
		(24 "In11.Cu" signal "IN4")
		(26 "In12.Cu" signal "GND5")
		(28 "In13.Cu" signal "IN5")
		(30 "In14.Cu" signal "GND6")
		(32 "In15.Cu" signal "IN6")
		(34 "In16.Cu" signal "GND7")
		(2 "B.Cu" signal "BOTTOM")
		(9 "F.Adhes" user "F.Adhesive")
		(11 "B.Adhes" user "B.Adhesive")
		(13 "F.Paste" user "Package Geometry/Pastemask Top")
		(15 "B.Paste" user "Package Geometry/Pastemask Bottom")
		(5 "F.SilkS" user "Ref Des/Silkscreen Top")
		(7 "B.SilkS" user "Ref Des/Silkscreen Bottom")
		(1 "F.Mask" user "Board Geometry/Soldermask Top")
		(3 "B.Mask" user "Board Geometry/Soldermask Bottom")
		(17 "Dwgs.User" user "User.Drawings")
		(19 "Cmts.User" user "User.Comments")
		(21 "Eco1.User" user "User.Eco1")
		(23 "Eco2.User" user "User.Eco2")
		(25 "Edge.Cuts" user "Board Geometry/Outline")
		(27 "Margin" user)
		(31 "F.CrtYd" user "Package Geometry/Place Bound Top")
		(29 "B.CrtYd" user "Package Geometry/Place Bound Bottom")
		(35 "F.Fab" user "Ref Des/Assembly Top")
		(33 "B.Fab" user "Ref Des/Assembly Bottom")
	)
	(footprint ""
		(layer "F.Cu")
		(at 362.991908 -338.17814 -90)
		(property "Reference" "PC279"
			(at 0 0 270)
			(layer "F.SilkS")
			(hide yes)
			(effects
				(font
					(size 1.27 1.27)
				)
			)
		)
		(property "Value" ""
			(at 0 0 270)
			(layer "F.Fab")
			(effects
				(font
					(size 1.27 1.27)
				)
			)
		)
		(duplicate_pad_numbers_are_jumpers no)
		(fp_line
			(start -0.7874 0.4064)
			(end -0.7874 -0.4064)
			(stroke
				(width 0.1524)
				(type default)
			)
			(layer "F.SilkS")
		)
		(fp_line
			(start 0.7874 0.4064)
			(end -0.7874 0.4064)
			(stroke
				(width 0.1524)
				(type default)
			)
			(layer "F.SilkS")
		)
		(fp_line
			(start -0.7874 -0.4064)
			(end 0.7874 -0.4064)
			(stroke
				(width 0.1524)
				(type default)
			)
			(layer "F.SilkS")
		)
		(fp_line
			(start 0.7874 -0.4064)
			(end 0.7874 0.4064)
			(stroke
				(width 0.1524)
				(type default)
			)
			(layer "F.SilkS")
		)
		(fp_line
			(start -0.67945 0.3048)
			(end -0.67945 -0.305054)
			(stroke
				(width 0.1)
				(type default)
			)
			(layer "F.Fab")
		)
		(fp_line
			(start -0.12065 0.3048)
			(end -0.67945 0.3048)
			(stroke
				(width 0.1)
				(type default)
			)
			(layer "F.Fab")
		)
		(fp_line
			(start 0.120396 0.3048)
			(end 0.120396 0.2794)
			(stroke
				(width 0.1)
				(type default)
			)
			(layer "F.Fab")
		)
		(fp_line
			(start 0.67945 0.3048)
			(end 0.120396 0.3048)
			(stroke
				(width 0.1)
				(type default)
			)
			(layer "F.Fab")
		)
		(fp_line
			(start -0.12065 0.2794)
			(end -0.12065 0.3048)
			(stroke
				(width 0.1)
				(type default)
			)
			(layer "F.Fab")
		)
		(fp_line
			(start 0.120396 0.2794)
			(end -0.12065 0.2794)
			(stroke
				(width 0.1)
				(type default)
			)
			(layer "F.Fab")
		)
		(fp_line
			(start -0.12065 -0.2794)
			(end 0.12065 -0.2794)
			(stroke
				(width 0.1)
				(type default)
			)
			(layer "F.Fab")
		)
		(fp_line
			(start 0.12065 -0.2794)
			(end 0.12065 -0.3048)
			(stroke
				(width 0.1)
				(type default)
			)
			(layer "F.Fab")
		)
		(fp_line
			(start 0.12065 -0.3048)
			(end 0.67945 -0.3048)
			(stroke
				(width 0.1)
				(type default)
			)
			(layer "F.Fab")
		)
		(fp_line
			(start 0.67945 -0.3048)
			(end 0.67945 0.3048)
			(stroke
				(width 0.1)
				(type default)
			)
			(layer "F.Fab")
		)
		(fp_line
			(start -0.67945 -0.305054)
			(end -0.12065 -0.305054)
			(stroke
				(width 0.1)
				(type default)
			)
			(layer "F.Fab")
		)
		(fp_line
			(start -0.12065 -0.305054)
			(end -0.12065 -0.2794)
			(stroke
				(width 0.1)
				(type default)
			)
			(layer "F.Fab")
		)
		(pad "1" smd circle
			(at -0.40005 0 270)
			(size 0 0)
			(layers "F.Cu" "F.Mask" "F.Paste")
			(net "SW_PVCCIN_CPU0_BOOT3_R")
		)
		(pad "2" smd circle
			(at 0.40005 0 270)
			(size 0 0)
			(layers "F.Cu" "F.Mask" "F.Paste")
			(net "SW_PVCCIN_CPU0_BOOTR3")
		)
	)
	(footprint ""
		(layer "F.Cu")
		(at 179.2224 -93.538548 90)
		(property "Reference" "R4591"
			(at 0 0 90)
			(layer "F.SilkS")
			(hide yes)
			(effects
				(font
					(size 1.27 1.27)
				)
			)
		)
		(property "Value" ""
			(at 0 0 90)
			(layer "F.Fab")
			(effects
				(font
					(size 1.27 1.27)
				)
			)
		)
		(duplicate_pad_numbers_are_jumpers no)
		(fp_line
			(start 0.7874 -0.4064)
			(end 0.7874 0.4064)
			(stroke
				(width 0.1524)
				(type default)
			)
			(layer "F.SilkS")
		)
		(fp_line
			(start -0.7874 -0.4064)
			(end 0.7874 -0.4064)
			(stroke
				(width 0.1524)
				(type default)
			)
			(layer "F.SilkS")
		)
		(fp_line
			(start 0.7874 0.4064)
			(end -0.7874 0.4064)
			(stroke
				(width 0.1524)
				(type default)
			)
			(layer "F.SilkS")
		)
		(fp_line
			(start -0.7874 0.4064)
			(end -0.7874 -0.4064)
			(stroke
				(width 0.1524)
				(type default)
			)
			(layer "F.SilkS")
		)
		(fp_line
			(start -0.12065 -0.305054)
			(end -0.12065 -0.2794)
			(stroke
				(width 0.1)
				(type default)
			)
			(layer "F.Fab")
		)
		(fp_line
			(start -0.67945 -0.305054)
			(end -0.12065 -0.305054)
			(stroke
				(width 0.1)
				(type default)
			)
			(layer "F.Fab")
		)
		(fp_line
			(start 0.67945 -0.3048)
			(end 0.67945 0.3048)
			(stroke
				(width 0.1)
				(type default)
			)
			(layer "F.Fab")
		)
		(fp_line
			(start 0.12065 -0.3048)
			(end 0.67945 -0.3048)
			(stroke
				(width 0.1)
				(type default)
			)
			(layer "F.Fab")
		)
		(fp_line
			(start 0.12065 -0.2794)
			(end 0.12065 -0.3048)
			(stroke
				(width 0.1)
				(type default)
			)
			(layer "F.Fab")
		)
		(fp_line
			(start -0.12065 -0.2794)
			(end 0.12065 -0.2794)
			(stroke
				(width 0.1)
				(type default)
			)
			(layer "F.Fab")
		)
		(fp_line
			(start 0.120396 0.2794)
			(end -0.12065 0.2794)
			(stroke
				(width 0.1)
				(type default)
			)
			(layer "F.Fab")
		)
		(fp_line
			(start -0.12065 0.2794)
			(end -0.12065 0.3048)
			(stroke
				(width 0.1)
				(type default)
			)
			(layer "F.Fab")
		)
		(fp_line
			(start 0.67945 0.3048)
			(end 0.120396 0.3048)
			(stroke
				(width 0.1)
				(type default)
			)
			(layer "F.Fab")
		)
		(fp_line
			(start 0.120396 0.3048)
			(end 0.120396 0.2794)
			(stroke
				(width 0.1)
				(type default)
			)
			(layer "F.Fab")
		)
		(fp_line
			(start -0.12065 0.3048)
			(end -0.67945 0.3048)
			(stroke
				(width 0.1)
				(type default)
			)
			(layer "F.Fab")
		)
		(fp_line
			(start -0.67945 0.3048)
			(end -0.67945 -0.305054)
			(stroke
				(width 0.1)
				(type default)
			)
			(layer "F.Fab")
		)
		(pad "1" smd rect
			(at -0.40005 0 270)
			(size 0.4572 0.508)
			(layers "F.Cu" "F.Mask" "F.Paste")
			(net "P3V3_AUX")
		)
		(pad "2" smd rect
			(at 0.40005 0 270)
			(size 0.4572 0.508)
			(layers "F.Cu" "F.Mask" "F.Paste")
			(net "FM_BOARD_BMC_SKU_ID3")
		)
	)
	(footprint ""
		(layer "F.Cu")
		(at 100.382832 -47.049944)
		(property "Reference" "H32"
			(at -1.7272 -4.511548 0)
			(unlocked yes)
			(layer "B.SilkS")
			(effects
				(font
					(size 0.7874 0.5842)
					(thickness 0.1524)
				)
				(justify left mirror)
			)
		)
		(property "Value" ""
			(at 0 0 0)
			(layer "F.Fab")
			(effects
				(font
					(size 1.27 1.27)
				)
			)
		)
		(duplicate_pad_numbers_are_jumpers no)
		(pad "1" thru_hole circle
			(at 0 0)
			(size 4.5212 4.5212)
			(drill 3.81)
			(layers "*.Cu" "*.Mask")
			(remove_unused_layers no)
			(net "GND")
			(clearance -0.1016)
			(padstack
				(mode front_inner_back)
				(layer "Inner"
					(shape circle)
					(size 5.6134 5.6134)
					(clearance -0.6477)
				)
				(layer "B.Cu"
					(shape circle)
					(size 8.001 8.001)
					(clearance -1.8415)
				)
			)
		)
	)
	(footprint ""
		(layer "F.Cu")
		(at 335.002124 -25.954482 -90)
		(property "Reference" "R1870"
			(at 0 0 270)
			(layer "F.SilkS")
			(hide yes)
			(effects
				(font
					(size 1.27 1.27)
				)
			)
		)
		(property "Value" ""
			(at 0 0 270)
			(layer "F.Fab")
			(effects
				(font
					(size 1.27 1.27)
				)
			)
		)
		(duplicate_pad_numbers_are_jumpers no)
		(fp_line
			(start -0.7874 0.4064)
			(end -0.7874 -0.4064)
			(stroke
				(width 0.1524)
				(type default)
			)
			(layer "F.SilkS")
		)
		(fp_line
			(start 0.7874 0.4064)
			(end -0.7874 0.4064)
			(stroke
				(width 0.1524)
				(type default)
			)
			(layer "F.SilkS")
		)
		(fp_line
			(start -0.7874 -0.4064)
			(end 0.7874 -0.4064)
			(stroke
				(width 0.1524)
				(type default)
			)
			(layer "F.SilkS")
		)
		(fp_line
			(start 0.7874 -0.4064)
			(end 0.7874 0.4064)
			(stroke
				(width 0.1524)
				(type default)
			)
			(layer "F.SilkS")
		)
		(fp_line
			(start -0.67945 0.3048)
			(end -0.67945 -0.305054)
			(stroke
				(width 0.1)
				(type default)
			)
			(layer "F.Fab")
		)
		(fp_line
			(start -0.12065 0.3048)
			(end -0.67945 0.3048)
			(stroke
				(width 0.1)
				(type default)
			)
			(layer "F.Fab")
		)
		(fp_line
			(start 0.120396 0.3048)
			(end 0.120396 0.2794)
			(stroke
				(width 0.1)
				(type default)
			)
			(layer "F.Fab")
		)
		(fp_line
			(start 0.67945 0.3048)
			(end 0.120396 0.3048)
			(stroke
				(width 0.1)
				(type default)
			)
			(layer "F.Fab")
		)
		(fp_line
			(start -0.12065 0.2794)
			(end -0.12065 0.3048)
			(stroke
				(width 0.1)
				(type default)
			)
			(layer "F.Fab")
		)
		(fp_line
			(start 0.120396 0.2794)
			(end -0.12065 0.2794)
			(stroke
				(width 0.1)
				(type default)
			)
			(layer "F.Fab")
		)
		(fp_line
			(start -0.12065 -0.2794)
			(end 0.12065 -0.2794)
			(stroke
				(width 0.1)
				(type default)
			)
			(layer "F.Fab")
		)
		(fp_line
			(start 0.12065 -0.2794)
			(end 0.12065 -0.3048)
			(stroke
				(width 0.1)
				(type default)
			)
			(layer "F.Fab")
		)
		(fp_line
			(start 0.12065 -0.3048)
			(end 0.67945 -0.3048)
			(stroke
				(width 0.1)
				(type default)
			)
			(layer "F.Fab")
		)
		(fp_line
			(start 0.67945 -0.3048)
			(end 0.67945 0.3048)
			(stroke
				(width 0.1)
				(type default)
			)
			(layer "F.Fab")
		)
		(fp_line
			(start -0.67945 -0.305054)
			(end -0.12065 -0.305054)
			(stroke
				(width 0.1)
				(type default)
			)
			(layer "F.Fab")
		)
		(fp_line
			(start -0.12065 -0.305054)
			(end -0.12065 -0.2794)
			(stroke
				(width 0.1)
				(type default)
			)
			(layer "F.Fab")
		)
		(pad "1" smd circle
			(at -0.40005 0 270)
			(size 0 0)
			(layers "F.Cu" "F.Mask" "F.Paste")
			(net "ESPI_LAD0_DATA_IO1")
		)
		(pad "2" smd circle
			(at 0.40005 0 270)
			(size 0 0)
			(layers "F.Cu" "F.Mask" "F.Paste")
			(net "ESPI_LPC_LAD0_IO1")
		)
	)
	(footprint ""
		(layer "F.Cu")
		(at 356.54488 -296.05478)
		(property "Reference" "C216"
			(at 0 0 0)
			(layer "F.SilkS")
			(hide yes)
			(effects
				(font
					(size 1.27 1.27)
				)
			)
		)
		(property "Value" ""
			(at 0 0 0)
			(layer "F.Fab")
			(effects
				(font
					(size 1.27 1.27)
				)
			)
		)
		(duplicate_pad_numbers_are_jumpers no)
		(fp_line
			(start -1.524 -0.762)
			(end 1.524 -0.762)
			(stroke
				(width 0.1524)
				(type default)
			)
			(layer "F.SilkS")
		)
		(fp_line
			(start -1.524 0.762)
			(end -1.524 -0.762)
			(stroke
				(width 0.1524)
				(type default)
			)
			(layer "F.SilkS")
		)
		(fp_line
			(start 1.524 -0.762)
			(end 1.524 0.762)
			(stroke
				(width 0.1524)
				(type default)
			)
			(layer "F.SilkS")
		)
		(fp_line
			(start 1.524 0.762)
			(end -1.524 0.762)
			(stroke
				(width 0.1524)
				(type default)
			)
			(layer "F.SilkS")
		)
		(fp_line
			(start -1.1049 -0.724916)
			(end -1.1049 0.724916)
			(stroke
				(width 0.1)
				(type default)
			)
			(layer "F.Fab")
		)
		(fp_line
			(start -1.1049 0.724916)
			(end 1.1049 0.724916)
			(stroke
				(width 0.1)
				(type default)
			)
			(layer "F.Fab")
		)
		(fp_line
			(start 1.1049 -0.724916)
			(end -1.1049 -0.724916)
			(stroke
				(width 0.1)
				(type default)
			)
			(layer "F.Fab")
		)
		(fp_line
			(start 1.1049 0.724916)
			(end 1.1049 -0.724916)
			(stroke
				(width 0.1)
				(type default)
			)
			(layer "F.Fab")
		)
		(pad "1" smd rect
			(at -0.889 0 180)
			(size 1.016 1.27)
			(layers "F.Cu" "F.Mask" "F.Paste")
			(net "PVCCIN_CPU0")
		)
		(pad "2" smd rect
			(at 0.889 0 180)
			(size 1.016 1.27)
			(layers "F.Cu" "F.Mask" "F.Paste")
			(net "GND")
		)
	)
	(footprint ""
		(layer "F.Cu")
		(at 24.892 -420.5732 180)
		(property "Reference" "R4741"
			(at 0 0 180)
			(layer "F.SilkS")
			(hide yes)
			(effects
				(font
					(size 1.27 1.27)
				)
			)
		)
		(property "Value" ""
			(at 0 0 180)
			(layer "F.Fab")
			(effects
				(font
					(size 1.27 1.27)
				)
			)
		)
		(duplicate_pad_numbers_are_jumpers no)
		(fp_line
			(start 0.7874 0.4064)
			(end -0.7874 0.4064)
			(stroke
				(width 0.1524)
				(type default)
			)
			(layer "F.SilkS")
		)
		(fp_line
			(start 0.7874 -0.4064)
			(end 0.7874 0.4064)
			(stroke
				(width 0.1524)
				(type default)
			)
			(layer "F.SilkS")
		)
		(fp_line
			(start -0.7874 0.4064)
			(end -0.7874 -0.4064)
			(stroke
				(width 0.1524)
				(type default)
			)
			(layer "F.SilkS")
		)
		(fp_line
			(start -0.7874 -0.4064)
			(end 0.7874 -0.4064)
			(stroke
				(width 0.1524)
				(type default)
			)
			(layer "F.SilkS")
		)
		(fp_line
			(start 0.67945 0.3048)
			(end 0.120396 0.3048)
			(stroke
				(width 0.1)
				(type default)
			)
			(layer "F.Fab")
		)
		(fp_line
			(start 0.67945 -0.3048)
			(end 0.67945 0.3048)
			(stroke
				(width 0.1)
				(type default)
			)
			(layer "F.Fab")
		)
		(fp_line
			(start 0.12065 -0.2794)
			(end 0.12065 -0.3048)
			(stroke
				(width 0.1)
				(type default)
			)
			(layer "F.Fab")
		)
		(fp_line
			(start 0.12065 -0.3048)
			(end 0.67945 -0.3048)
			(stroke
				(width 0.1)
				(type default)
			)
			(layer "F.Fab")
		)
		(fp_line
			(start 0.120396 0.3048)
			(end 0.120396 0.2794)
			(stroke
				(width 0.1)
				(type default)
			)
			(layer "F.Fab")
		)
		(fp_line
			(start 0.120396 0.2794)
			(end -0.12065 0.2794)
			(stroke
				(width 0.1)
				(type default)
			)
			(layer "F.Fab")
		)
		(fp_line
			(start -0.12065 0.3048)
			(end -0.67945 0.3048)
			(stroke
				(width 0.1)
				(type default)
			)
			(layer "F.Fab")
		)
		(fp_line
			(start -0.12065 0.2794)
			(end -0.12065 0.3048)
			(stroke
				(width 0.1)
				(type default)
			)
			(layer "F.Fab")
		)
		(fp_line
			(start -0.12065 -0.2794)
			(end 0.12065 -0.2794)
			(stroke
				(width 0.1)
				(type default)
			)
			(layer "F.Fab")
		)
		(fp_line
			(start -0.12065 -0.305054)
			(end -0.12065 -0.2794)
			(stroke
				(width 0.1)
				(type default)
			)
			(layer "F.Fab")
		)
		(fp_line
			(start -0.67945 0.3048)
			(end -0.67945 -0.305054)
			(stroke
				(width 0.1)
				(type default)
			)
			(layer "F.Fab")
		)
		(fp_line
			(start -0.67945 -0.305054)
			(end -0.12065 -0.305054)
			(stroke
				(width 0.1)
				(type default)
			)
			(layer "F.Fab")
		)
		(pad "1" smd circle
			(at -0.40005 0 180)
			(size 0 0)
			(layers "F.Cu" "F.Mask" "F.Paste")
			(net "PRSNT_CABLE_SWB_B1_ISO_N")
		)
		(pad "2" smd circle
			(at 0.40005 0 180)
			(size 0 0)
			(layers "F.Cu" "F.Mask" "F.Paste")
			(net "PRSNT_CABLE_SWB_B1_ISO_R_N")
		)
	)
	(footprint ""
		(layer "F.Cu")
		(at 328.913998 -190.74511 -90)
		(property "Reference" "R4263"
			(at 0 0 270)
			(layer "F.SilkS")
			(hide yes)
			(effects
				(font
					(size 1.27 1.27)
				)
			)
		)
		(property "Value" ""
			(at 0 0 270)
			(layer "F.Fab")
			(effects
				(font
					(size 1.27 1.27)
				)
			)
		)
		(duplicate_pad_numbers_are_jumpers no)
		(fp_line
			(start -0.7874 0.4064)
			(end -0.7874 -0.4064)
			(stroke
				(width 0.1524)
				(type default)
			)
			(layer "F.SilkS")
		)
		(fp_line
			(start 0.7874 0.4064)
			(end -0.7874 0.4064)
			(stroke
				(width 0.1524)
				(type default)
			)
			(layer "F.SilkS")
		)
		(fp_line
			(start -0.7874 -0.4064)
			(end 0.7874 -0.4064)
			(stroke
				(width 0.1524)
				(type default)
			)
			(layer "F.SilkS")
		)
		(fp_line
			(start 0.7874 -0.4064)
			(end 0.7874 0.4064)
			(stroke
				(width 0.1524)
				(type default)
			)
			(layer "F.SilkS")
		)
		(fp_line
			(start -0.67945 0.3048)
			(end -0.67945 -0.305054)
			(stroke
				(width 0.1)
				(type default)
			)
			(layer "F.Fab")
		)
		(fp_line
			(start -0.12065 0.3048)
			(end -0.67945 0.3048)
			(stroke
				(width 0.1)
				(type default)
			)
			(layer "F.Fab")
		)
		(fp_line
			(start 0.120396 0.3048)
			(end 0.120396 0.2794)
			(stroke
				(width 0.1)
				(type default)
			)
			(layer "F.Fab")
		)
		(fp_line
			(start 0.67945 0.3048)
			(end 0.120396 0.3048)
			(stroke
				(width 0.1)
				(type default)
			)
			(layer "F.Fab")
		)
		(fp_line
			(start -0.12065 0.2794)
			(end -0.12065 0.3048)
			(stroke
				(width 0.1)
				(type default)
			)
			(layer "F.Fab")
		)
		(fp_line
			(start 0.120396 0.2794)
			(end -0.12065 0.2794)
			(stroke
				(width 0.1)
				(type default)
			)
			(layer "F.Fab")
		)
		(fp_line
			(start -0.12065 -0.2794)
			(end 0.12065 -0.2794)
			(stroke
				(width 0.1)
				(type default)
			)
			(layer "F.Fab")
		)
		(fp_line
			(start 0.12065 -0.2794)
			(end 0.12065 -0.3048)
			(stroke
				(width 0.1)
				(type default)
			)
			(layer "F.Fab")
		)
		(fp_line
			(start 0.12065 -0.3048)
			(end 0.67945 -0.3048)
			(stroke
				(width 0.1)
				(type default)
			)
			(layer "F.Fab")
		)
		(fp_line
			(start 0.67945 -0.3048)
			(end 0.67945 0.3048)
			(stroke
				(width 0.1)
				(type default)
			)
			(layer "F.Fab")
		)
		(fp_line
			(start -0.67945 -0.305054)
			(end -0.12065 -0.305054)
			(stroke
				(width 0.1)
				(type default)
			)
			(layer "F.Fab")
		)
		(fp_line
			(start -0.12065 -0.305054)
			(end -0.12065 -0.2794)
			(stroke
				(width 0.1)
				(type default)
			)
			(layer "F.Fab")
		)
		(pad "1" smd circle
			(at -0.40005 0 270)
			(size 0 0)
			(layers "F.Cu" "F.Mask" "F.Paste")
			(net "PD_CPU0_BIST_ENABLE")
		)
		(pad "2" smd circle
			(at 0.40005 0 270)
			(size 0 0)
			(layers "F.Cu" "F.Mask" "F.Paste")
			(net "GND")
		)
	)
)
